(kicad_pcb
	(version 20241229)
	(generator "pcbnew")
	(generator_version "9.0")
	(general
		(thickness 1.63)
		(legacy_teardrops no)
	)
	(paper "A4")
	(title_block
		(title "CM4 Baseboard")
		(date "2026-01-05")
		(rev "1.1.1")
		(company "Antmicro Ltd")
		(comment 1 "www.antmicro.com")
		(comment 9 "footprints 216-219 of 506")
	)
	(layers
		(0 "F.Cu" signal)
		(4 "In1.Cu" power)
		(6 "In2.Cu" power)
		(8 "In3.Cu" signal)
		(10 "In4.Cu" signal)
		(2 "B.Cu" signal)
		(9 "F.Adhes" user "F.Adhesive")
		(11 "B.Adhes" user "B.Adhesive")
		(13 "F.Paste" user)
		(15 "B.Paste" user)
		(5 "F.SilkS" user "F.Silkscreen")
		(7 "B.SilkS" user "B.Silkscreen")
		(1 "F.Mask" user)
		(3 "B.Mask" user)
		(17 "Dwgs.User" user "User.Drawings")
		(19 "Cmts.User" user "User.Comments")
		(21 "Eco1.User" user "User.Eco1")
		(23 "Eco2.User" user "User.Eco2")
		(25 "Edge.Cuts" user)
		(27 "Margin" user)
		(31 "F.CrtYd" user "F.Courtyard")
		(29 "B.CrtYd" user "B.Courtyard")
		(35 "F.Fab" user)
		(33 "B.Fab" user)
	)
	(footprint "antmicro-footprints:C_0402_1005Metric"
		(layer "F.Cu")
		(at 63.61 174.2415)
		(descr "Capacitor SMD 0402")
		(tags "capacitor SMD 0402")
		(property "Reference" "C823"
			(at -13.36 -2.9915 0)
			(layer "F.SilkS")
			(effects
				(font
					(size 0.7 0.7)
					(thickness 0.15)
				)
				(justify right top)
			)
		)
		(property "Value" "C_template_name_0402"
			(at -1.022927 2.155213 0)
			(layer "F.Fab")
			(effects
				(font
					(size 0.7 0.7)
					(thickness 0.15)
				)
				(justify left bottom)
			)
		)
		(property "Datasheet" "template_datasheet"
			(at 0 0 0)
			(layer "F.Fab")
			(hide yes)
			(effects
				(font
					(size 1.27 1.27)
					(thickness 0.15)
				)
			)
		)
		(property "MPN" "template_MPN"
			(at 0 0 0)
			(unlocked yes)
			(layer "F.Fab")
			(hide yes)
			(effects
				(font
					(size 1 1)
					(thickness 0.15)
				)
			)
		)
		(property "Manufacturer" "template_manufacturer"
			(at 0 0 0)
			(unlocked yes)
			(layer "F.Fab")
			(hide yes)
			(effects
				(font
					(size 1 1)
					(thickness 0.15)
				)
			)
		)
		(property "License" "Apache-2.0"
			(at 0 0 0)
			(unlocked yes)
			(layer "F.Fab")
			(hide yes)
			(effects
				(font
					(size 1 1)
					(thickness 0.15)
				)
			)
		)
		(property "Author" "Antmicro"
			(at 0 0 0)
			(unlocked yes)
			(layer "F.Fab")
			(hide yes)
			(effects
				(font
					(size 1 1)
					(thickness 0.15)
				)
			)
		)
		(property "Val" "template_value"
			(at 0 0 0)
			(unlocked yes)
			(layer "F.Fab")
			(hide yes)
			(effects
				(font
					(size 1 1)
					(thickness 0.15)
				)
			)
		)
		(property "Voltage" "template_voltage"
			(at 0 0 0)
			(unlocked yes)
			(layer "F.Fab")
			(hide yes)
			(effects
				(font
					(size 1 1)
					(thickness 0.15)
				)
			)
		)
		(property "Dielectric" "template_dielectric"
			(at 0 0 0)
			(unlocked yes)
			(layer "F.Fab")
			(hide yes)
			(effects
				(font
					(size 1 1)
					(thickness 0.15)
				)
			)
		)
		(sheetname "/Peripherals/")
		(sheetfile "peripherals.kicad_sch")
		(attr smd exclude_from_pos_files exclude_from_bom dnp)
		(fp_rect
			(start -0.925 -0.47)
			(end 0.925 0.47)
			(stroke
				(width 0.05)
				(type default)
			)
			(fill no)
			(layer "F.CrtYd")
		)
		(fp_line
			(start -0.494 -0.25)
			(end 0.504 -0.25)
			(stroke
				(width 0.15)
				(type solid)
			)
			(layer "F.Fab")
		)
		(fp_line
			(start -0.494 0.248)
			(end -0.494 -0.25)
			(stroke
				(width 0.15)
				(type solid)
			)
			(layer "F.Fab")
		)
		(fp_line
			(start 0.504 -0.25)
			(end 0.504 0.248)
			(stroke
				(width 0.15)
				(type solid)
			)
			(layer "F.Fab")
		)
		(fp_line
			(start 0.504 0.248)
			(end -0.494 0.248)
			(stroke
				(width 0.15)
				(type solid)
			)
			(layer "F.Fab")
		)
		(fp_text user "License: Apache-2.0"
			(at -0.939 5.799 0)
			(layer "F.Fab")
			(effects
				(font
					(size 0.7 0.7)
					(thickness 0.15)
				)
				(justify left bottom)
			)
		)
		(fp_text user "Author: Antmicro"
			(at -0.939 3.399 0)
			(layer "F.Fab")
			(effects
				(font
					(size 0.7 0.7)
					(thickness 0.15)
				)
				(justify left bottom)
			)
		)
		(fp_text user "${REFERENCE}"
			(at -0.939 4.599 0)
			(layer "F.Fab")
			(effects
				(font
					(size 0.7 0.7)
					(thickness 0.15)
				)
				(justify left bottom)
			)
		)
		(pad "1" smd roundrect
			(at -0.48 0)
			(size 0.59 0.64)
			(layers "F.Cu" "F.Mask" "F.Paste")
			(roundrect_rratio 0.25)
			(net 106 "Net-(C814-Pad2)")
			(pintype "passive")
		)
		(pad "2" smd roundrect
			(at 0.48 0)
			(size 0.59 0.64)
			(layers "F.Cu" "F.Mask" "F.Paste")
			(roundrect_rratio 0.25)
			(net 110 "Net-(C817-Pad1)")
			(pintype "passive")
		)
	)
	(footprint "antmicro-footprints:Nexperia_DFN-10_2.5x1mm_P0.5mm"
		(layer "F.Cu")
		(at 142.292962 141.4165 90)
		(property "Reference" "D804"
			(at 2.61 0.155 90)
			(layer "F.SilkS")
			(effects
				(font
					(size 0.7 0.7)
					(thickness 0.15)
				)
				(justify left bottom)
			)
		)
		(property "Value" "PUSB3F96X_PASS"
			(at -0.016 1.705 90)
			(layer "F.Fab")
			(effects
				(font
					(size 0.7 0.7)
					(thickness 0.15)
				)
				(justify left bottom)
			)
		)
		(property "Datasheet" "https://mouser.com/datasheet/2/916/PUSB3F96-1600324.pdf"
			(at 0 0 90)
			(layer "F.Fab")
			(hide yes)
			(effects
				(font
					(size 1.27 1.27)
					(thickness 0.15)
				)
			)
		)
		(property "Manufacturer" "Nexperia"
			(at 0 0 90)
			(unlocked yes)
			(layer "F.Fab")
			(hide yes)
			(effects
				(font
					(size 1 1)
					(thickness 0.15)
				)
			)
		)
		(property "MPN" "PUSB3F96X"
			(at 0 0 90)
			(unlocked yes)
			(layer "F.Fab")
			(hide yes)
			(effects
				(font
					(size 1 1)
					(thickness 0.15)
				)
			)
		)
		(property "Author" "Antmicro"
			(at 0 0 90)
			(unlocked yes)
			(layer "F.Fab")
			(hide yes)
			(effects
				(font
					(size 1 1)
					(thickness 0.15)
				)
			)
		)
		(property "License" "Apache-2.0"
			(at 0 0 90)
			(unlocked yes)
			(layer "F.Fab")
			(hide yes)
			(effects
				(font
					(size 1 1)
					(thickness 0.15)
				)
			)
		)
		(sheetname "/Peripherals/")
		(sheetfile "peripherals.kicad_sch")
		(attr smd)
		(fp_line
			(start -1.375 -0.4)
			(end -1.375 0.4)
			(stroke
				(width 0.15)
				(type solid)
			)
			(layer "F.SilkS")
		)
		(fp_line
			(start 1.375 0.4)
			(end 1.375 -0.4)
			(stroke
				(width 0.15)
				(type solid)
			)
			(layer "F.SilkS")
		)
		(fp_circle
			(center -1.4 0.7)
			(end -1.349 0.7)
			(stroke
				(width 0.15)
				(type solid)
			)
			(fill yes)
			(layer "F.SilkS")
		)
		(fp_rect
			(start -1.4 -0.725)
			(end 1.4 0.725)
			(stroke
				(width 0.05)
				(type solid)
			)
			(fill no)
			(layer "F.CrtYd")
		)
		(fp_line
			(start 1.25 -0.5)
			(end -1.25 -0.5)
			(stroke
				(width 0.15)
				(type solid)
			)
			(layer "F.Fab")
		)
		(fp_line
			(start -1.25 -0.5)
			(end -1.25 0.15)
			(stroke
				(width 0.15)
				(type solid)
			)
			(layer "F.Fab")
		)
		(fp_line
			(start -1.25 0.15)
			(end -0.9 0.5)
			(stroke
				(width 0.15)
				(type solid)
			)
			(layer "F.Fab")
		)
		(fp_line
			(start 1.25 0.5)
			(end 1.25 -0.5)
			(stroke
				(width 0.15)
				(type solid)
			)
			(layer "F.Fab")
		)
		(fp_line
			(start -0.9 0.5)
			(end 1.25 0.5)
			(stroke
				(width 0.15)
				(type solid)
			)
			(layer "F.Fab")
		)
		(fp_text user "Author: Antmicro"
			(at -1.367 4.905 90)
			(layer "F.Fab")
			(effects
				(font
					(size 0.7 0.7)
					(thickness 0.15)
				)
				(justify left bottom)
			)
		)
		(fp_text user "License: Apache-2.0"
			(at -1.367 6.105 90)
			(layer "F.Fab")
			(effects
				(font
					(size 0.7 0.7)
					(thickness 0.15)
				)
				(justify left bottom)
			)
		)
		(fp_text user "${REFERENCE}"
			(at -1.367 3.704 90)
			(layer "F.Fab")
			(effects
				(font
					(size 0.7 0.7)
					(thickness 0.15)
				)
				(justify left bottom)
			)
		)
		(pad "1" smd rect
			(at -1 0.3875 90)
			(size 0.2 0.475)
			(layers "F.Cu" "F.Mask" "F.Paste")
			(net 223 "/Compute module/GPIO.6")
			(pinfunction "CH1")
			(pintype "passive")
			(solder_mask_margin 0.05)
		)
		(pad "2" smd rect
			(at -0.5 0.3875 90)
			(size 0.2 0.475)
			(layers "F.Cu" "F.Mask" "F.Paste")
			(net 221 "/Compute module/GPIO.13{slash}TXD5")
			(pinfunction "CH2")
			(pintype "passive")
			(solder_mask_margin 0.05)
		)
		(pad "3" smd rect
			(at 0 0.3875 90)
			(size 0.2 0.475)
			(layers "F.Cu" "F.Mask" "F.Paste")
			(net 3 "GND")
			(pinfunction "GND")
			(pintype "passive")
			(solder_mask_margin 0.05)
		)
		(pad "4" smd rect
			(at 0.5 0.3875 90)
			(size 0.2 0.475)
			(layers "F.Cu" "F.Mask" "F.Paste")
			(net 219 "/Compute module/GPIO.19")
			(pinfunction "CH3")
			(pintype "passive")
			(solder_mask_margin 0.05)
		)
		(pad "5" smd rect
			(at 1 0.3875 90)
			(size 0.2 0.475)
			(layers "F.Cu" "F.Mask" "F.Paste")
			(net 217 "/Compute module/GPIO.26")
			(pinfunction "CH4")
			(pintype "passive")
			(solder_mask_margin 0.05)
		)
		(pad "6" smd rect
			(at 1 -0.3875 90)
			(size 0.2 0.475)
			(layers "F.Cu" "F.Mask" "F.Paste")
			(net 217 "/Compute module/GPIO.26")
			(pinfunction "CH4")
			(pintype "passive")
			(solder_mask_margin 0.05)
		)
		(pad "7" smd rect
			(at 0.5 -0.3875 90)
			(size 0.2 0.475)
			(layers "F.Cu" "F.Mask" "F.Paste")
			(net 219 "/Compute module/GPIO.19")
			(pinfunction "CH3")
			(pintype "passive")
			(solder_mask_margin 0.05)
		)
		(pad "8" smd rect
			(at 0 -0.3875 90)
			(size 0.2 0.475)
			(layers "F.Cu" "F.Mask" "F.Paste")
			(net 3 "GND")
			(pinfunction "GND")
			(pintype "passive")
			(solder_mask_margin 0.05)
		)
		(pad "9" smd rect
			(at -0.501 -0.3875 90)
			(size 0.2 0.475)
			(layers "F.Cu" "F.Mask" "F.Paste")
			(net 221 "/Compute module/GPIO.13{slash}TXD5")
			(pinfunction "CH2")
			(pintype "passive")
			(solder_mask_margin 0.05)
		)
		(pad "10" smd rect
			(at -1 -0.3875 90)
			(size 0.2 0.475)
			(layers "F.Cu" "F.Mask" "F.Paste")
			(net 223 "/Compute module/GPIO.6")
			(pinfunction "CH1")
			(pintype "passive")
			(solder_mask_margin 0.05)
		)
	)
	(footprint "antmicro-footprints:LED_0603_1608Metric_G"
		(layer "F.Cu")
		(at 73.767962 158.4865 180)
		(descr "LED SMD 0603 Green")
		(tags "LED SMD 0603 Green")
		(property "Reference" "D304"
			(at 6.15 0.42 0)
			(layer "F.SilkS")
			(effects
				(font
					(size 0.7 0.7)
					(thickness 0.15)
				)
				(justify right bottom)
			)
		)
		(property "Value" "LED_G_0603_KP-1608CGCK"
			(at -0.001 1.599 0)
			(layer "F.Fab")
			(effects
				(font
					(size 0.7 0.7)
					(thickness 0.15)
				)
				(justify right bottom)
			)
		)
		(property "Datasheet" "http://www.kingbright.com/attachments/file/psearch//000/00/00/KP-1608CGCK(Ver.23B).pdf"
			(at 0 0 180)
			(layer "F.Fab")
			(hide yes)
			(effects
				(font
					(size 1.27 1.27)
					(thickness 0.15)
				)
			)
		)
		(property "MPN" "KP-1608CGCK"
			(at 0 0 180)
			(unlocked yes)
			(layer "F.Fab")
			(hide yes)
			(effects
				(font
					(size 1 1)
					(thickness 0.15)
				)
			)
		)
		(property "Manufacturer" "Kingbright"
			(at 0 0 180)
			(unlocked yes)
			(layer "F.Fab")
			(hide yes)
			(effects
				(font
					(size 1 1)
					(thickness 0.15)
				)
			)
		)
		(property "Color" "Green"
			(at 0 0 180)
			(unlocked yes)
			(layer "F.Fab")
			(hide yes)
			(effects
				(font
					(size 1 1)
					(thickness 0.15)
				)
			)
		)
		(property "Author" "Antmicro"
			(at 0 0 180)
			(unlocked yes)
			(layer "F.Fab")
			(hide yes)
			(effects
				(font
					(size 1 1)
					(thickness 0.15)
				)
			)
		)
		(property "License" "Apache-2.0"
			(at 0 0 180)
			(unlocked yes)
			(layer "F.Fab")
			(hide yes)
			(effects
				(font
					(size 1 1)
					(thickness 0.15)
				)
			)
		)
		(sheetname "/Supply/")
		(sheetfile "supply.kicad_sch")
		(attr smd)
		(fp_line
			(start 0.22 0.35)
			(end -0.22 0.35)
			(stroke
				(width 0.15)
				(type solid)
			)
			(layer "F.SilkS")
		)
		(fp_line
			(start 0.22 -0.35)
			(end -0.22 -0.35)
			(stroke
				(width 0.15)
				(type solid)
			)
			(layer "F.SilkS")
		)
		(fp_line
			(start 0.105328 0.201008)
			(end 0.105328 -0.198992)
			(stroke
				(width 0.1)
				(type solid)
			)
			(layer "F.SilkS")
		)
		(fp_line
			(start 0.105328 0.201008)
			(end -0.094672 0.001008)
			(stroke
				(width 0.1)
				(type solid)
			)
			(layer "F.SilkS")
		)
		(fp_line
			(start 0.105328 0.001008)
			(end 0.24 0.001)
			(stroke
				(width 0.1)
				(type solid)
			)
			(layer "F.SilkS")
		)
		(fp_line
			(start -0.094672 0.201008)
			(end -0.094672 -0.198992)
			(stroke
				(width 0.1)
				(type solid)
			)
			(layer "F.SilkS")
		)
		(fp_line
			(start -0.094672 0.001008)
			(end 0.105328 -0.198992)
			(stroke
				(width 0.1)
				(type solid)
			)
			(layer "F.SilkS")
		)
		(fp_line
			(start -0.094672 0.001008)
			(end -0.24 0.001008)
			(stroke
				(width 0.1)
				(type solid)
			)
			(layer "F.SilkS")
		)
		(fp_line
			(start -1.18 -0.319)
			(end -1.18 0.321)
			(stroke
				(width 0.15)
				(type solid)
			)
			(layer "F.SilkS")
		)
		(fp_rect
			(start 1.25 0.65)
			(end -1.25 -0.65)
			(stroke
				(width 0.05)
				(type solid)
			)
			(fill no)
			(layer "F.CrtYd")
		)
		(fp_line
			(start 0.599 0)
			(end 0.201 0)
			(stroke
				(width 0.15)
				(type solid)
			)
			(layer "F.Fab")
		)
		(fp_line
			(start 0.201 0.2)
			(end 0.201 0)
			(stroke
				(width 0.15)
				(type solid)
			)
			(layer "F.Fab")
		)
		(fp_line
			(start 0.201 0)
			(end 0.201 -0.202)
			(stroke
				(width 0.15)
				(type solid)
			)
			(layer "F.Fab")
		)
		(fp_line
			(start 0.201 -0.202)
			(end -0.101 0)
			(stroke
				(width 0.15)
				(type solid)
			)
			(layer "F.Fab")
		)
		(fp_line
			(start -0.101 0)
			(end 0.201 0.2)
			(stroke
				(width 0.15)
				(type solid)
			)
			(layer "F.Fab")
		)
		(fp_line
			(start -0.199 0.2)
			(end -0.199 0.1)
			(stroke
				(width 0.15)
				(type solid)
			)
			(layer "F.Fab")
		)
		(fp_line
			(start -0.199 0)
			(end -0.597 0)
			(stroke
				(width 0.15)
				(type solid)
			)
			(layer "F.Fab")
		)
		(fp_line
			(start -0.199 -0.202)
			(end -0.199 0.1)
			(stroke
				(width 0.15)
				(type solid)
			)
			(layer "F.Fab")
		)
		(fp_rect
			(start 0.848 0.4)
			(end -0.85 -0.402)
			(stroke
				(width 0.15)
				(type solid)
			)
			(fill no)
			(layer "F.Fab")
		)
		(fp_text user "License: Apache-2.0"
			(at -1.4224 3.599 180)
			(layer "F.Fab")
			(effects
				(font
					(size 0.7 0.7)
					(thickness 0.15)
				)
				(justify left bottom)
			)
		)
		(fp_text user "Author: Antmicro"
			(at -1.4224 4.799 180)
			(layer "F.Fab")
			(effects
				(font
					(size 0.7 0.7)
					(thickness 0.15)
				)
				(justify left bottom)
			)
		)
		(fp_text user "${REFERENCE}"
			(at -1.4224 5.999 180)
			(layer "F.Fab")
			(effects
				(font
					(size 0.7 0.7)
					(thickness 0.15)
				)
				(justify left bottom)
			)
		)
		(pad "1" smd roundrect
			(at -0.7 0)
			(size 0.8 1)
			(layers "F.Cu" "F.Mask" "F.Paste")
			(roundrect_rratio 0.2)
			(net 3 "GND")
			(pinfunction "C")
			(pintype "passive")
		)
		(pad "2" smd roundrect
			(at 0.7 0)
			(size 0.8 1)
			(layers "F.Cu" "F.Mask" "F.Paste")
			(roundrect_rratio 0.2)
			(net 474 "Net-(D304-A)")
			(pinfunction "A")
			(pintype "passive")
		)
	)
	(footprint "antmicro-footprints:C_0402_1005Metric"
		(layer "F.Cu")
		(at 92.142962 144.3165 -90)
		(descr "Capacitor SMD 0402")
		(tags "capacitor SMD 0402")
		(property "Reference" "C914"
			(at 0.425 -2.225 90)
			(layer "F.SilkS")
			(effects
				(font
					(size 0.7 0.7)
					(thickness 0.15)
				)
				(justify right bottom)
			)
		)
		(property "Value" "C_100n_0402"
			(at -1.022927 2.155213 90)
			(layer "F.Fab")
			(effects
				(font
					(size 0.7 0.7)
					(thickness 0.15)
				)
				(justify right bottom)
			)
		)
		(property "Datasheet" "https://www.murata.com/products/productdetail?partno=GRM155R61H104KE14%23"
			(at 0 0 270)
			(layer "F.Fab")
			(hide yes)
			(effects
				(font
					(size 1.27 1.27)
					(thickness 0.15)
				)
			)
		)
		(property "Manufacturer" "Murata"
			(at 0 0 270)
			(unlocked yes)
			(layer "F.Fab")
			(hide yes)
			(effects
				(font
					(size 1 1)
					(thickness 0.15)
				)
			)
		)
		(property "MPN" "GRM155R61H104KE14D"
			(at 0 0 270)
			(unlocked yes)
			(layer "F.Fab")
			(hide yes)
			(effects
				(font
					(size 1 1)
					(thickness 0.15)
				)
			)
		)
		(property "Val" "100n"
			(at 0 0 270)
			(unlocked yes)
			(layer "F.Fab")
			(hide yes)
			(effects
				(font
					(size 1 1)
					(thickness 0.15)
				)
			)
		)
		(property "License" "Apache-2.0"
			(at 0 0 270)
			(unlocked yes)
			(layer "F.Fab")
			(hide yes)
			(effects
				(font
					(size 1 1)
					(thickness 0.15)
				)
			)
		)
		(property "Author" "Antmicro"
			(at 0 0 270)
			(unlocked yes)
			(layer "F.Fab")
			(hide yes)
			(effects
				(font
					(size 1 1)
					(thickness 0.15)
				)
			)
		)
		(property "Voltage" "50V"
			(at 0 0 270)
			(unlocked yes)
			(layer "F.Fab")
			(hide yes)
			(effects
				(font
					(size 1 1)
					(thickness 0.15)
				)
			)
		)
		(property "Dielectric" "X5R"
			(at 0 0 270)
			(unlocked yes)
			(layer "F.Fab")
			(hide yes)
			(effects
				(font
					(size 1 1)
					(thickness 0.15)
				)
			)
		)
		(sheetname "/USB/")
		(sheetfile "usb.kicad_sch")
		(attr smd)
		(fp_rect
			(start -0.925 -0.47)
			(end 0.925 0.47)
			(stroke
				(width 0.05)
				(type default)
			)
			(fill no)
			(layer "F.CrtYd")
		)
		(fp_line
			(start -0.494 0.248)
			(end -0.494 -0.25)
			(stroke
				(width 0.15)
				(type solid)
			)
			(layer "F.Fab")
		)
		(fp_line
			(start 0.504 0.248)
			(end -0.494 0.248)
			(stroke
				(width 0.15)
				(type solid)
			)
			(layer "F.Fab")
		)
		(fp_line
			(start -0.494 -0.25)
			(end 0.504 -0.25)
			(stroke
				(width 0.15)
				(type solid)
			)
			(layer "F.Fab")
		)
		(fp_line
			(start 0.504 -0.25)
			(end 0.504 0.248)
			(stroke
				(width 0.15)
				(type solid)
			)
			(layer "F.Fab")
		)
		(fp_text user "License: Apache-2.0"
			(at -0.939 5.799 270)
			(layer "F.Fab")
			(effects
				(font
					(size 0.7 0.7)
					(thickness 0.15)
				)
				(justify left bottom)
			)
		)
		(fp_text user "${REFERENCE}"
			(at -0.939 4.599 270)
			(layer "F.Fab")
			(effects
				(font
					(size 0.7 0.7)
					(thickness 0.15)
				)
				(justify left bottom)
			)
		)
		(fp_text user "Author: Antmicro"
			(at -0.939 3.399 270)
			(layer "F.Fab")
			(effects
				(font
					(size 0.7 0.7)
					(thickness 0.15)
				)
				(justify left bottom)
			)
		)
		(pad "1" smd roundrect
			(at -0.48 0 270)
			(size 0.59 0.64)
			(layers "F.Cu" "F.Mask" "F.Paste")
			(roundrect_rratio 0.25)
			(net 30 "/USB/USB_1V2")
			(pintype "passive")
		)
		(pad "2" smd roundrect
			(at 0.48 0 270)
			(size 0.59 0.64)
			(layers "F.Cu" "F.Mask" "F.Paste")
			(roundrect_rratio 0.25)
			(net 3 "GND")
			(pintype "passive")
		)
	)
)
